# S9S_MB_2U (Grand Teton) — schematic netlist excerpt (pin names and nets, part order shuffled) for the footprints in the layout excerpt that follows; sources: Cadence DE-HDL packaged netlist, KiCad conversion of 03242023_DA0F0TMBIJ0_F0T_Motherboard_J_brd_V01_OCP.brd

R4606  Q_RES  0 5% CHIP  pkg 0402LF  page 214 : A = E1S_0_LED_ACT_R_N ; B = E1S_0_LED_ACT_N
R2596  Q_RES  150 1% CHIP  pkg 0402LF  page 274 : A = SVID_CLK0_CPU0_R ; B = SVID_CLK_PVCCINFAON_CPU0_R

(kicad_pcb
	(version 20260206)
	(generator "pcbnew")
	(generator_version "10.0")
	(general
		(thickness 1.6)
		(legacy_teardrops no)
	)
	(paper "A4")
	(title_block
		(title "03242023_DA0F0TMBIJ0_F0T_Motherboard_J_brd_V01_OCP.brd")
		(comment 1 "Grand Teton / footprints 2156-2157 of 6105")
	)
	(layers
		(0 "F.Cu" signal "TOP")
		(4 "In1.Cu" signal "GND")
		(6 "In2.Cu" signal "IN1")
		(8 "In3.Cu" signal "GND1")
		(10 "In4.Cu" signal "IN2")
		(12 "In5.Cu" signal "GND2")
		(14 "In6.Cu" signal "IN3")
		(16 "In7.Cu" signal "GND3")
		(18 "In8.Cu" signal "VCC")
		(20 "In9.Cu" signal "VCC1")
		(22 "In10.Cu" signal "GND4")
		(24 "In11.Cu" signal "IN4")
		(26 "In12.Cu" signal "GND5")
		(28 "In13.Cu" signal "IN5")
		(30 "In14.Cu" signal "GND6")
		(32 "In15.Cu" signal "IN6")
		(34 "In16.Cu" signal "GND7")
		(2 "B.Cu" signal "BOTTOM")
		(9 "F.Adhes" user "F.Adhesive")
		(11 "B.Adhes" user "B.Adhesive")
		(13 "F.Paste" user "Package Geometry/Pastemask Top")
		(15 "B.Paste" user "Package Geometry/Pastemask Bottom")
		(5 "F.SilkS" user "Ref Des/Silkscreen Top")
		(7 "B.SilkS" user "Ref Des/Silkscreen Bottom")
		(1 "F.Mask" user "Board Geometry/Soldermask Top")
		(3 "B.Mask" user "Board Geometry/Soldermask Bottom")
		(17 "Dwgs.User" user "User.Drawings")
		(19 "Cmts.User" user "User.Comments")
		(21 "Eco1.User" user "User.Eco1")
		(23 "Eco2.User" user "User.Eco2")
		(25 "Edge.Cuts" user "Board Geometry/Outline")
		(27 "Margin" user)
		(31 "F.CrtYd" user "Package Geometry/Place Bound Top")
		(29 "B.CrtYd" user "Package Geometry/Place Bound Bottom")
		(35 "F.Fab" user "Ref Des/Assembly Top")
		(33 "B.Fab" user "Ref Des/Assembly Bottom")
	)
	(footprint ""
		(layer "F.Cu")
		(at 194.056 -92.801948 90)
		(property "Reference" "R4606"
			(at 0 0 90)
			(layer "F.SilkS")
			(hide yes)
			(effects
				(font
					(size 1.27 1.27)
				)
			)
		)
		(property "Value" ""
			(at 0 0 90)
			(layer "F.Fab")
			(effects
				(font
					(size 1.27 1.27)
				)
			)
		)
		(duplicate_pad_numbers_are_jumpers no)
		(fp_line
			(start 0.7874 -0.4064)
			(end 0.7874 0.4064)
			(stroke
				(width 0.1524)
				(type default)
			)
			(layer "F.SilkS")
		)
		(fp_line
			(start -0.7874 -0.4064)
			(end 0.7874 -0.4064)
			(stroke
				(width 0.1524)
				(type default)
			)
			(layer "F.SilkS")
		)
		(fp_line
			(start 0.7874 0.4064)
			(end -0.7874 0.4064)
			(stroke
				(width 0.1524)
				(type default)
			)
			(layer "F.SilkS")
		)
		(fp_line
			(start -0.7874 0.4064)
			(end -0.7874 -0.4064)
			(stroke
				(width 0.1524)
				(type default)
			)
			(layer "F.SilkS")
		)
		(fp_line
			(start -0.12065 -0.305054)
			(end -0.12065 -0.2794)
			(stroke
				(width 0.1)
				(type default)
			)
			(layer "F.Fab")
		)
		(fp_line
			(start -0.67945 -0.305054)
			(end -0.12065 -0.305054)
			(stroke
				(width 0.1)
				(type default)
			)
			(layer "F.Fab")
		)
		(fp_line
			(start 0.67945 -0.3048)
			(end 0.67945 0.3048)
			(stroke
				(width 0.1)
				(type default)
			)
			(layer "F.Fab")
		)
		(fp_line
			(start 0.12065 -0.3048)
			(end 0.67945 -0.3048)
			(stroke
				(width 0.1)
				(type default)
			)
			(layer "F.Fab")
		)
		(fp_line
			(start 0.12065 -0.2794)
			(end 0.12065 -0.3048)
			(stroke
				(width 0.1)
				(type default)
			)
			(layer "F.Fab")
		)
		(fp_line
			(start -0.12065 -0.2794)
			(end 0.12065 -0.2794)
			(stroke
				(width 0.1)
				(type default)
			)
			(layer "F.Fab")
		)
		(fp_line
			(start 0.120396 0.2794)
			(end -0.12065 0.2794)
			(stroke
				(width 0.1)
				(type default)
			)
			(layer "F.Fab")
		)
		(fp_line
			(start -0.12065 0.2794)
			(end -0.12065 0.3048)
			(stroke
				(width 0.1)
				(type default)
			)
			(layer "F.Fab")
		)
		(fp_line
			(start 0.67945 0.3048)
			(end 0.120396 0.3048)
			(stroke
				(width 0.1)
				(type default)
			)
			(layer "F.Fab")
		)
		(fp_line
			(start 0.120396 0.3048)
			(end 0.120396 0.2794)
			(stroke
				(width 0.1)
				(type default)
			)
			(layer "F.Fab")
		)
		(fp_line
			(start -0.12065 0.3048)
			(end -0.67945 0.3048)
			(stroke
				(width 0.1)
				(type default)
			)
			(layer "F.Fab")
		)
		(fp_line
			(start -0.67945 0.3048)
			(end -0.67945 -0.305054)
			(stroke
				(width 0.1)
				(type default)
			)
			(layer "F.Fab")
		)
		(pad "1" smd circle
			(at -0.40005 0 90)
			(size 0 0)
			(layers "F.Cu" "F.Mask" "F.Paste")
			(net "E1S_0_LED_ACT_R_N")
		)
		(pad "2" smd circle
			(at 0.40005 0 90)
			(size 0 0)
			(layers "F.Cu" "F.Mask" "F.Paste")
			(net "E1S_0_LED_ACT_N")
		)
	)
	(footprint ""
		(layer "F.Cu")
		(at 430.600104 -136.526778 180)
		(property "Reference" "R2596"
			(at 0 0 180)
			(layer "F.SilkS")
			(hide yes)
			(effects
				(font
					(size 1.27 1.27)
				)
			)
		)
		(property "Value" ""
			(at 0 0 180)
			(layer "F.Fab")
			(effects
				(font
					(size 1.27 1.27)
				)
			)
		)
		(duplicate_pad_numbers_are_jumpers no)
		(fp_line
			(start 0.7874 0.4064)
			(end -0.7874 0.4064)
			(stroke
				(width 0.1524)
				(type default)
			)
			(layer "F.SilkS")
		)
		(fp_line
			(start 0.7874 -0.4064)
			(end 0.7874 0.4064)
			(stroke
				(width 0.1524)
				(type default)
			)
			(layer "F.SilkS")
		)
		(fp_line
			(start -0.7874 0.4064)
			(end -0.7874 -0.4064)
			(stroke
				(width 0.1524)
				(type default)
			)
			(layer "F.SilkS")
		)
		(fp_line
			(start -0.7874 -0.4064)
			(end 0.7874 -0.4064)
			(stroke
				(width 0.1524)
				(type default)
			)
			(layer "F.SilkS")
		)
		(fp_line
			(start 0.67945 0.3048)
			(end 0.120396 0.3048)
			(stroke
				(width 0.1)
				(type default)
			)
			(layer "F.Fab")
		)
		(fp_line
			(start 0.67945 -0.3048)
			(end 0.67945 0.3048)
			(stroke
				(width 0.1)
				(type default)
			)
			(layer "F.Fab")
		)
		(fp_line
			(start 0.12065 -0.2794)
			(end 0.12065 -0.3048)
			(stroke
				(width 0.1)
				(type default)
			)
			(layer "F.Fab")
		)
		(fp_line
			(start 0.12065 -0.3048)
			(end 0.67945 -0.3048)
			(stroke
				(width 0.1)
				(type default)
			)
			(layer "F.Fab")
		)
		(fp_line
			(start 0.120396 0.3048)
			(end 0.120396 0.2794)
			(stroke
				(width 0.1)
				(type default)
			)
			(layer "F.Fab")
		)
		(fp_line
			(start 0.120396 0.2794)
			(end -0.12065 0.2794)
			(stroke
				(width 0.1)
				(type default)
			)
			(layer "F.Fab")
		)
		(fp_line
			(start -0.12065 0.3048)
			(end -0.67945 0.3048)
			(stroke
				(width 0.1)
				(type default)
			)
			(layer "F.Fab")
		)
		(fp_line
			(start -0.12065 0.2794)
			(end -0.12065 0.3048)
			(stroke
				(width 0.1)
				(type default)
			)
			(layer "F.Fab")
		)
		(fp_line
			(start -0.12065 -0.2794)
			(end 0.12065 -0.2794)
			(stroke
				(width 0.1)
				(type default)
			)
			(layer "F.Fab")
		)
		(fp_line
			(start -0.12065 -0.305054)
			(end -0.12065 -0.2794)
			(stroke
				(width 0.1)
				(type default)
			)
			(layer "F.Fab")
		)
		(fp_line
			(start -0.67945 0.3048)
			(end -0.67945 -0.305054)
			(stroke
				(width 0.1)
				(type default)
			)
			(layer "F.Fab")
		)
		(fp_line
			(start -0.67945 -0.305054)
			(end -0.12065 -0.305054)
			(stroke
				(width 0.1)
				(type default)
			)
			(layer "F.Fab")
		)
		(pad "1" smd circle
			(at -0.40005 0 180)
			(size 0 0)
			(layers "F.Cu" "F.Mask" "F.Paste")
			(net "SVID_CLK0_CPU0_R")
		)
		(pad "2" smd circle
			(at 0.40005 0 180)
			(size 0 0)
			(layers "F.Cu" "F.Mask" "F.Paste")
			(net "SVID_CLK_PVCCINFAON_CPU0_R")
		)
	)
)
